# S9S_MB_2U (Grand Teton) — schematic netlist excerpt (pin names and nets, part order shuffled) for the footprints in the layout excerpt that follows; sources: Cadence DE-HDL packaged netlist, KiCad conversion of 03242023_DA0F0TMBIJ0_F0T_Motherboard_J_brd_V01_OCP.brd

C1767  Q_CAP  10UF 16V 10% EMPTY  pkg C0805  page 250 : A = MAX11617_VREF ; B = GND
R1454  Q_RES  2K 1% CHIP  pkg 0402LF  page 183 : A = PU_SMB_SML4_3V3AUX_PCH_SDA ; B = P3V3_AUX
C422  Q_CAP  22UF 4V 20% X6S  pkg C0402  page 74 : A = PVCCFA_EHV_CPU0 ; B = GND

(kicad_pcb
	(version 20260206)
	(generator "pcbnew")
	(generator_version "10.0")
	(general
		(thickness 1.6)
		(legacy_teardrops no)
	)
	(paper "A4")
	(title_block
		(title "03242023_DA0F0TMBIJ0_F0T_Motherboard_J_brd_V01_OCP.brd")
		(comment 1 "Grand Teton / footprints 156-158 of 6105")
	)
	(layers
		(0 "F.Cu" signal "TOP")
		(4 "In1.Cu" signal "GND")
		(6 "In2.Cu" signal "IN1")
		(8 "In3.Cu" signal "GND1")
		(10 "In4.Cu" signal "IN2")
		(12 "In5.Cu" signal "GND2")
		(14 "In6.Cu" signal "IN3")
		(16 "In7.Cu" signal "GND3")
		(18 "In8.Cu" signal "VCC")
		(20 "In9.Cu" signal "VCC1")
		(22 "In10.Cu" signal "GND4")
		(24 "In11.Cu" signal "IN4")
		(26 "In12.Cu" signal "GND5")
		(28 "In13.Cu" signal "IN5")
		(30 "In14.Cu" signal "GND6")
		(32 "In15.Cu" signal "IN6")
		(34 "In16.Cu" signal "GND7")
		(2 "B.Cu" signal "BOTTOM")
		(9 "F.Adhes" user "F.Adhesive")
		(11 "B.Adhes" user "B.Adhesive")
		(13 "F.Paste" user "Package Geometry/Pastemask Top")
		(15 "B.Paste" user "Package Geometry/Pastemask Bottom")
		(5 "F.SilkS" user "Ref Des/Silkscreen Top")
		(7 "B.SilkS" user "Ref Des/Silkscreen Bottom")
		(1 "F.Mask" user "Board Geometry/Soldermask Top")
		(3 "B.Mask" user "Board Geometry/Soldermask Bottom")
		(17 "Dwgs.User" user "User.Drawings")
		(19 "Cmts.User" user "User.Comments")
		(21 "Eco1.User" user "User.Eco1")
		(23 "Eco2.User" user "User.Eco2")
		(25 "Edge.Cuts" user "Board Geometry/Outline")
		(27 "Margin" user)
		(31 "F.CrtYd" user "Package Geometry/Place Bound Top")
		(29 "B.CrtYd" user "Package Geometry/Place Bound Bottom")
		(35 "F.Fab" user "Ref Des/Assembly Top")
		(33 "B.Fab" user "Ref Des/Assembly Bottom")
	)
	(footprint ""
		(layer "F.Cu")
		(at 353.235514 -256.654046 -90)
		(property "Reference" "C422"
			(at 0 0 270)
			(layer "F.SilkS")
			(hide yes)
			(effects
				(font
					(size 1.27 1.27)
				)
			)
		)
		(property "Value" ""
			(at 0 0 270)
			(layer "F.Fab")
			(effects
				(font
					(size 1.27 1.27)
				)
			)
		)
		(duplicate_pad_numbers_are_jumpers no)
		(fp_line
			(start -0.7874 0.4064)
			(end -0.7874 -0.4064)
			(stroke
				(width 0.1524)
				(type default)
			)
			(layer "F.SilkS")
		)
		(fp_line
			(start 0.7874 0.4064)
			(end -0.7874 0.4064)
			(stroke
				(width 0.1524)
				(type default)
			)
			(layer "F.SilkS")
		)
		(fp_line
			(start -0.7874 -0.4064)
			(end 0.7874 -0.4064)
			(stroke
				(width 0.1524)
				(type default)
			)
			(layer "F.SilkS")
		)
		(fp_line
			(start 0.7874 -0.4064)
			(end 0.7874 0.4064)
			(stroke
				(width 0.1524)
				(type default)
			)
			(layer "F.SilkS")
		)
		(fp_line
			(start -0.67945 0.3048)
			(end -0.67945 -0.305054)
			(stroke
				(width 0.1)
				(type default)
			)
			(layer "F.Fab")
		)
		(fp_line
			(start -0.12065 0.3048)
			(end -0.67945 0.3048)
			(stroke
				(width 0.1)
				(type default)
			)
			(layer "F.Fab")
		)
		(fp_line
			(start 0.120396 0.3048)
			(end 0.120396 0.2794)
			(stroke
				(width 0.1)
				(type default)
			)
			(layer "F.Fab")
		)
		(fp_line
			(start 0.67945 0.3048)
			(end 0.120396 0.3048)
			(stroke
				(width 0.1)
				(type default)
			)
			(layer "F.Fab")
		)
		(fp_line
			(start -0.12065 0.2794)
			(end -0.12065 0.3048)
			(stroke
				(width 0.1)
				(type default)
			)
			(layer "F.Fab")
		)
		(fp_line
			(start 0.120396 0.2794)
			(end -0.12065 0.2794)
			(stroke
				(width 0.1)
				(type default)
			)
			(layer "F.Fab")
		)
		(fp_line
			(start -0.12065 -0.2794)
			(end 0.12065 -0.2794)
			(stroke
				(width 0.1)
				(type default)
			)
			(layer "F.Fab")
		)
		(fp_line
			(start 0.12065 -0.2794)
			(end 0.12065 -0.3048)
			(stroke
				(width 0.1)
				(type default)
			)
			(layer "F.Fab")
		)
		(fp_line
			(start 0.12065 -0.3048)
			(end 0.67945 -0.3048)
			(stroke
				(width 0.1)
				(type default)
			)
			(layer "F.Fab")
		)
		(fp_line
			(start 0.67945 -0.3048)
			(end 0.67945 0.3048)
			(stroke
				(width 0.1)
				(type default)
			)
			(layer "F.Fab")
		)
		(fp_line
			(start -0.67945 -0.305054)
			(end -0.12065 -0.305054)
			(stroke
				(width 0.1)
				(type default)
			)
			(layer "F.Fab")
		)
		(fp_line
			(start -0.12065 -0.305054)
			(end -0.12065 -0.2794)
			(stroke
				(width 0.1)
				(type default)
			)
			(layer "F.Fab")
		)
		(pad "1" smd circle
			(at -0.40005 0 270)
			(size 0 0)
			(layers "F.Cu" "F.Mask" "F.Paste")
			(net "PVCCFA_EHV_CPU0")
		)
		(pad "2" smd circle
			(at 0.40005 0 270)
			(size 0 0)
			(layers "F.Cu" "F.Mask" "F.Paste")
			(net "GND")
		)
	)
	(footprint ""
		(layer "F.Cu")
		(at 312.448194 -32.869886 180)
		(property "Reference" "R1454"
			(at 0 0 180)
			(layer "F.SilkS")
			(hide yes)
			(effects
				(font
					(size 1.27 1.27)
				)
			)
		)
		(property "Value" ""
			(at 0 0 180)
			(layer "F.Fab")
			(effects
				(font
					(size 1.27 1.27)
				)
			)
		)
		(duplicate_pad_numbers_are_jumpers no)
		(fp_line
			(start 0.7874 0.4064)
			(end -0.7874 0.4064)
			(stroke
				(width 0.1524)
				(type default)
			)
			(layer "F.SilkS")
		)
		(fp_line
			(start 0.7874 -0.4064)
			(end 0.7874 0.4064)
			(stroke
				(width 0.1524)
				(type default)
			)
			(layer "F.SilkS")
		)
		(fp_line
			(start -0.7874 0.4064)
			(end -0.7874 -0.4064)
			(stroke
				(width 0.1524)
				(type default)
			)
			(layer "F.SilkS")
		)
		(fp_line
			(start -0.7874 -0.4064)
			(end 0.7874 -0.4064)
			(stroke
				(width 0.1524)
				(type default)
			)
			(layer "F.SilkS")
		)
		(fp_line
			(start 0.67945 0.3048)
			(end 0.120396 0.3048)
			(stroke
				(width 0.1)
				(type default)
			)
			(layer "F.Fab")
		)
		(fp_line
			(start 0.67945 -0.3048)
			(end 0.67945 0.3048)
			(stroke
				(width 0.1)
				(type default)
			)
			(layer "F.Fab")
		)
		(fp_line
			(start 0.12065 -0.2794)
			(end 0.12065 -0.3048)
			(stroke
				(width 0.1)
				(type default)
			)
			(layer "F.Fab")
		)
		(fp_line
			(start 0.12065 -0.3048)
			(end 0.67945 -0.3048)
			(stroke
				(width 0.1)
				(type default)
			)
			(layer "F.Fab")
		)
		(fp_line
			(start 0.120396 0.3048)
			(end 0.120396 0.2794)
			(stroke
				(width 0.1)
				(type default)
			)
			(layer "F.Fab")
		)
		(fp_line
			(start 0.120396 0.2794)
			(end -0.12065 0.2794)
			(stroke
				(width 0.1)
				(type default)
			)
			(layer "F.Fab")
		)
		(fp_line
			(start -0.12065 0.3048)
			(end -0.67945 0.3048)
			(stroke
				(width 0.1)
				(type default)
			)
			(layer "F.Fab")
		)
		(fp_line
			(start -0.12065 0.2794)
			(end -0.12065 0.3048)
			(stroke
				(width 0.1)
				(type default)
			)
			(layer "F.Fab")
		)
		(fp_line
			(start -0.12065 -0.2794)
			(end 0.12065 -0.2794)
			(stroke
				(width 0.1)
				(type default)
			)
			(layer "F.Fab")
		)
		(fp_line
			(start -0.12065 -0.305054)
			(end -0.12065 -0.2794)
			(stroke
				(width 0.1)
				(type default)
			)
			(layer "F.Fab")
		)
		(fp_line
			(start -0.67945 0.3048)
			(end -0.67945 -0.305054)
			(stroke
				(width 0.1)
				(type default)
			)
			(layer "F.Fab")
		)
		(fp_line
			(start -0.67945 -0.305054)
			(end -0.12065 -0.305054)
			(stroke
				(width 0.1)
				(type default)
			)
			(layer "F.Fab")
		)
		(pad "1" smd circle
			(at -0.40005 0 180)
			(size 0 0)
			(layers "F.Cu" "F.Mask" "F.Paste")
			(net "PU_SMB_SML4_3V3AUX_PCH_SDA")
		)
		(pad "2" smd circle
			(at 0.40005 0 180)
			(size 0 0)
			(layers "F.Cu" "F.Mask" "F.Paste")
			(net "P3V3_AUX")
		)
	)
	(footprint ""
		(layer "F.Cu")
		(at 27.046428 -102.888034 180)
		(property "Reference" "C1767"
			(at 0 0 180)
			(layer "F.SilkS")
			(hide yes)
			(effects
				(font
					(size 1.27 1.27)
				)
			)
		)
		(property "Value" ""
			(at 0 0 180)
			(layer "F.Fab")
			(effects
				(font
					(size 1.27 1.27)
				)
			)
		)
		(duplicate_pad_numbers_are_jumpers no)
		(fp_line
			(start 1.524 0.762)
			(end -1.524 0.762)
			(stroke
				(width 0.1524)
				(type default)
			)
			(layer "F.SilkS")
		)
		(fp_line
			(start 1.524 -0.762)
			(end 1.524 0.762)
			(stroke
				(width 0.1524)
				(type default)
			)
			(layer "F.SilkS")
		)
		(fp_line
			(start -1.524 0.762)
			(end -1.524 -0.762)
			(stroke
				(width 0.1524)
				(type default)
			)
			(layer "F.SilkS")
		)
		(fp_line
			(start -1.524 -0.762)
			(end 1.524 -0.762)
			(stroke
				(width 0.1524)
				(type default)
			)
			(layer "F.SilkS")
		)
		(fp_line
			(start 1.1049 0.724916)
			(end 1.1049 -0.724916)
			(stroke
				(width 0.1)
				(type default)
			)
			(layer "F.Fab")
		)
		(fp_line
			(start 1.1049 -0.724916)
			(end -1.1049 -0.724916)
			(stroke
				(width 0.1)
				(type default)
			)
			(layer "F.Fab")
		)
		(fp_line
			(start -1.1049 0.724916)
			(end 1.1049 0.724916)
			(stroke
				(width 0.1)
				(type default)
			)
			(layer "F.Fab")
		)
		(fp_line
			(start -1.1049 -0.724916)
			(end -1.1049 0.724916)
			(stroke
				(width 0.1)
				(type default)
			)
			(layer "F.Fab")
		)
		(pad "1" smd rect
			(at -0.889 0)
			(size 1.016 1.27)
			(layers "F.Cu" "F.Mask" "F.Paste")
			(net "MAX11617_VREF")
		)
		(pad "2" smd rect
			(at 0.889 0)
			(size 1.016 1.27)
			(layers "F.Cu" "F.Mask" "F.Paste")
			(net "GND")
		)
	)
)
